# SCM (Grand Teton) — schematic netlist excerpt (pin names and nets, part order shuffled) for the footprints in the layout excerpt that follows; sources: Cadence DE-HDL packaged netlist, KiCad conversion of 12092022_DA0F0TMDCD0_F0T_Management_Board_D_brd_V3_OCP.brd

R826  Q_RES  33.2 1% CHIP  pkg 0402LF  page 13 : A = IRQ_PCH_SCI_WHEA_R_N ; B = IRQ_PCH_SCI_WHEA_N
R489  Q_RES  33.2 1% CHIP  pkg 0402LF  page 15 : A = FM_SOL_UART_CH_SEL ; B = FM_SOL_UART_CH_SEL_R1

(kicad_pcb
	(version 20260206)
	(generator "pcbnew")
	(generator_version "10.0")
	(general
		(thickness 1.6)
		(legacy_teardrops no)
	)
	(paper "A4")
	(title_block
		(title "12092022_DA0F0TMDCD0_F0T_Management_Board_D_brd_V3_OCP.brd")
		(comment 1 "Grand Teton / footprints 996-997 of 1440")
	)
	(layers
		(0 "F.Cu" signal "TOP")
		(4 "In1.Cu" signal "GND")
		(6 "In2.Cu" signal "IN1")
		(8 "In3.Cu" signal "GND1")
		(10 "In4.Cu" signal "IN2")
		(12 "In5.Cu" signal "VCC")
		(14 "In6.Cu" signal "VCC1")
		(16 "In7.Cu" signal "IN3")
		(18 "In8.Cu" signal "GND2")
		(20 "In9.Cu" signal "IN4")
		(22 "In10.Cu" signal "GND3")
		(2 "B.Cu" signal "BOTTOM")
		(9 "F.Adhes" user "F.Adhesive")
		(11 "B.Adhes" user "B.Adhesive")
		(13 "F.Paste" user "Package Geometry/Pastemask Top")
		(15 "B.Paste" user "Package Geometry/Pastemask Bottom")
		(5 "F.SilkS" user "Ref Des/Silkscreen Top")
		(7 "B.SilkS" user "Ref Des/Silkscreen Bottom")
		(1 "F.Mask" user "Board Geometry/Soldermask Top")
		(3 "B.Mask" user "Board Geometry/Soldermask Bottom")
		(17 "Dwgs.User" user "User.Drawings")
		(19 "Cmts.User" user "User.Comments")
		(21 "Eco1.User" user "User.Eco1")
		(23 "Eco2.User" user "User.Eco2")
		(25 "Edge.Cuts" user "Board Geometry/Outline")
		(27 "Margin" user)
		(31 "F.CrtYd" user "Package Geometry/Place Bound Top")
		(29 "B.CrtYd" user "Package Geometry/Place Bound Bottom")
		(35 "F.Fab" user "Ref Des/Assembly Top")
		(33 "B.Fab" user "Ref Des/Assembly Bottom")
	)
	(footprint ""
		(layer "B.Cu")
		(at 53.5432 -34.637726 90)
		(property "Reference" "R826"
			(at 0 0 90)
			(layer "B.SilkS")
			(hide yes)
			(effects
				(font
					(size 1.27 1.27)
				)
				(justify mirror)
			)
		)
		(property "Value" ""
			(at 0 0 90)
			(layer "B.Fab")
			(effects
				(font
					(size 1.27 1.27)
				)
				(justify mirror)
			)
		)
		(duplicate_pad_numbers_are_jumpers no)
		(fp_line
			(start 0.7874 -0.4064)
			(end -0.7874 -0.4064)
			(stroke
				(width 0.1524)
				(type default)
			)
			(layer "B.SilkS")
		)
		(fp_line
			(start -0.7874 -0.4064)
			(end -0.7874 0.4064)
			(stroke
				(width 0.1524)
				(type default)
			)
			(layer "B.SilkS")
		)
		(fp_line
			(start 0.7874 0.4064)
			(end 0.7874 -0.4064)
			(stroke
				(width 0.1524)
				(type default)
			)
			(layer "B.SilkS")
		)
		(fp_line
			(start -0.7874 0.4064)
			(end 0.7874 0.4064)
			(stroke
				(width 0.1524)
				(type default)
			)
			(layer "B.SilkS")
		)
		(fp_line
			(start 0.67945 -0.305054)
			(end 0.12065 -0.305054)
			(stroke
				(width 0.1)
				(type default)
			)
			(layer "B.Fab")
		)
		(fp_line
			(start 0.12065 -0.305054)
			(end 0.12065 -0.2794)
			(stroke
				(width 0.1)
				(type default)
			)
			(layer "B.Fab")
		)
		(fp_line
			(start -0.12065 -0.3048)
			(end -0.67945 -0.3048)
			(stroke
				(width 0.1)
				(type default)
			)
			(layer "B.Fab")
		)
		(fp_line
			(start -0.67945 -0.3048)
			(end -0.67945 0.3048)
			(stroke
				(width 0.1)
				(type default)
			)
			(layer "B.Fab")
		)
		(fp_line
			(start 0.12065 -0.2794)
			(end -0.12065 -0.2794)
			(stroke
				(width 0.1)
				(type default)
			)
			(layer "B.Fab")
		)
		(fp_line
			(start -0.12065 -0.2794)
			(end -0.12065 -0.3048)
			(stroke
				(width 0.1)
				(type default)
			)
			(layer "B.Fab")
		)
		(fp_line
			(start 0.12065 0.2794)
			(end 0.12065 0.3048)
			(stroke
				(width 0.1)
				(type default)
			)
			(layer "B.Fab")
		)
		(fp_line
			(start -0.120396 0.2794)
			(end 0.12065 0.2794)
			(stroke
				(width 0.1)
				(type default)
			)
			(layer "B.Fab")
		)
		(fp_line
			(start 0.67945 0.3048)
			(end 0.67945 -0.305054)
			(stroke
				(width 0.1)
				(type default)
			)
			(layer "B.Fab")
		)
		(fp_line
			(start 0.12065 0.3048)
			(end 0.67945 0.3048)
			(stroke
				(width 0.1)
				(type default)
			)
			(layer "B.Fab")
		)
		(fp_line
			(start -0.120396 0.3048)
			(end -0.120396 0.2794)
			(stroke
				(width 0.1)
				(type default)
			)
			(layer "B.Fab")
		)
		(fp_line
			(start -0.67945 0.3048)
			(end -0.120396 0.3048)
			(stroke
				(width 0.1)
				(type default)
			)
			(layer "B.Fab")
		)
		(pad "1" smd circle
			(at 0.40005 0 270)
			(size 0 0)
			(layers "B.Cu" "B.Mask" "B.Paste")
			(net "IRQ_PCH_SCI_WHEA_R_N")
		)
		(pad "2" smd circle
			(at -0.40005 0 270)
			(size 0 0)
			(layers "B.Cu" "B.Mask" "B.Paste")
			(net "IRQ_PCH_SCI_WHEA_N")
		)
	)
	(footprint ""
		(layer "B.Cu")
		(at 45.0342 -55.4482 90)
		(property "Reference" "R489"
			(at 0 0 90)
			(layer "B.SilkS")
			(hide yes)
			(effects
				(font
					(size 1.27 1.27)
				)
				(justify mirror)
			)
		)
		(property "Value" ""
			(at 0 0 90)
			(layer "B.Fab")
			(effects
				(font
					(size 1.27 1.27)
				)
				(justify mirror)
			)
		)
		(duplicate_pad_numbers_are_jumpers no)
		(fp_line
			(start 0.7874 -0.4064)
			(end -0.7874 -0.4064)
			(stroke
				(width 0.1524)
				(type default)
			)
			(layer "B.SilkS")
		)
		(fp_line
			(start -0.7874 -0.4064)
			(end -0.7874 0.4064)
			(stroke
				(width 0.1524)
				(type default)
			)
			(layer "B.SilkS")
		)
		(fp_line
			(start 0.7874 0.4064)
			(end 0.7874 -0.4064)
			(stroke
				(width 0.1524)
				(type default)
			)
			(layer "B.SilkS")
		)
		(fp_line
			(start -0.7874 0.4064)
			(end 0.7874 0.4064)
			(stroke
				(width 0.1524)
				(type default)
			)
			(layer "B.SilkS")
		)
		(fp_line
			(start 0.67945 -0.305054)
			(end 0.12065 -0.305054)
			(stroke
				(width 0.1)
				(type default)
			)
			(layer "B.Fab")
		)
		(fp_line
			(start 0.12065 -0.305054)
			(end 0.12065 -0.2794)
			(stroke
				(width 0.1)
				(type default)
			)
			(layer "B.Fab")
		)
		(fp_line
			(start -0.12065 -0.3048)
			(end -0.67945 -0.3048)
			(stroke
				(width 0.1)
				(type default)
			)
			(layer "B.Fab")
		)
		(fp_line
			(start -0.67945 -0.3048)
			(end -0.67945 0.3048)
			(stroke
				(width 0.1)
				(type default)
			)
			(layer "B.Fab")
		)
		(fp_line
			(start 0.12065 -0.2794)
			(end -0.12065 -0.2794)
			(stroke
				(width 0.1)
				(type default)
			)
			(layer "B.Fab")
		)
		(fp_line
			(start -0.12065 -0.2794)
			(end -0.12065 -0.3048)
			(stroke
				(width 0.1)
				(type default)
			)
			(layer "B.Fab")
		)
		(fp_line
			(start 0.12065 0.2794)
			(end 0.12065 0.3048)
			(stroke
				(width 0.1)
				(type default)
			)
			(layer "B.Fab")
		)
		(fp_line
			(start -0.120396 0.2794)
			(end 0.12065 0.2794)
			(stroke
				(width 0.1)
				(type default)
			)
			(layer "B.Fab")
		)
		(fp_line
			(start 0.67945 0.3048)
			(end 0.67945 -0.305054)
			(stroke
				(width 0.1)
				(type default)
			)
			(layer "B.Fab")
		)
		(fp_line
			(start 0.12065 0.3048)
			(end 0.67945 0.3048)
			(stroke
				(width 0.1)
				(type default)
			)
			(layer "B.Fab")
		)
		(fp_line
			(start -0.120396 0.3048)
			(end -0.120396 0.2794)
			(stroke
				(width 0.1)
				(type default)
			)
			(layer "B.Fab")
		)
		(fp_line
			(start -0.67945 0.3048)
			(end -0.120396 0.3048)
			(stroke
				(width 0.1)
				(type default)
			)
			(layer "B.Fab")
		)
		(pad "1" smd circle
			(at 0.40005 0 270)
			(size 0 0)
			(layers "B.Cu" "B.Mask" "B.Paste")
			(net "FM_SOL_UART_CH_SEL")
		)
		(pad "2" smd circle
			(at -0.40005 0 270)
			(size 0 0)
			(layers "B.Cu" "B.Mask" "B.Paste")
			(net "FM_SOL_UART_CH_SEL_R1")
		)
	)
)
